(kicad_pcb
	(version 20260206)
	(generator "pcbnew")
	(generator_version "10.0")
	(general
		(thickness 1.6)
		(legacy_teardrops no)
	)
	(paper "A4")
	(title_block
		(title "04192023_DAF0TMB3IC0_F0TG_MB_C_brd_V02_OCP.brd")
		(comment 1 "Grand Teton / footprints 1006-1011 of 8354")
	)
	(layers
		(0 "F.Cu" signal "TOP")
		(4 "In1.Cu" signal "GND")
		(6 "In2.Cu" signal "IN1")
		(8 "In3.Cu" signal "GND1")
		(10 "In4.Cu" signal "IN2")
		(12 "In5.Cu" signal "GND2")
		(14 "In6.Cu" signal "IN3")
		(16 "In7.Cu" signal "GND3")
		(18 "In8.Cu" signal "VCC")
		(20 "In9.Cu" signal "VCC1")
		(22 "In10.Cu" signal "GND4")
		(24 "In11.Cu" signal "IN4")
		(26 "In12.Cu" signal "GND5")
		(28 "In13.Cu" signal "IN5")
		(30 "In14.Cu" signal "GND6")
		(32 "In15.Cu" signal "IN6")
		(34 "In16.Cu" signal "GND7")
		(2 "B.Cu" signal "BOTTOM")
		(9 "F.Adhes" user "F.Adhesive")
		(11 "B.Adhes" user "B.Adhesive")
		(13 "F.Paste" user "Package Geometry/Pastemask Top")
		(15 "B.Paste" user "Package Geometry/Pastemask Bottom")
		(5 "F.SilkS" user "Ref Des/Silkscreen Top")
		(7 "B.SilkS" user "Ref Des/Silkscreen Bottom")
		(1 "F.Mask" user "Board Geometry/Soldermask Top")
		(3 "B.Mask" user "Board Geometry/Soldermask Bottom")
		(17 "Dwgs.User" user "User.Drawings")
		(19 "Cmts.User" user "User.Comments")
		(21 "Eco1.User" user "User.Eco1")
		(23 "Eco2.User" user "User.Eco2")
		(25 "Edge.Cuts" user "Board Geometry/Outline")
		(27 "Margin" user)
		(31 "F.CrtYd" user "Package Geometry/Place Bound Top")
		(29 "B.CrtYd" user "Package Geometry/Place Bound Bottom")
		(35 "F.Fab" user "Ref Des/Assembly Top")
		(33 "B.Fab" user "Ref Des/Assembly Bottom")
	)
	(footprint ""
		(layer "F.Cu")
		(at 253.08941 -45.865542 90)
		(property "Reference" "PR3968"
			(at 0 0 90)
			(layer "F.SilkS")
			(hide yes)
			(effects
				(font
					(size 1.27 1.27)
				)
			)
		)
		(property "Value" ""
			(at 0 0 90)
			(layer "F.Fab")
			(effects
				(font
					(size 1.27 1.27)
				)
			)
		)
		(duplicate_pad_numbers_are_jumpers no)
		(fp_line
			(start 0.7874 -0.4064)
			(end 0.7874 0.4064)
			(stroke
				(width 0.1524)
				(type default)
			)
			(layer "F.SilkS")
		)
		(fp_line
			(start -0.7874 -0.4064)
			(end 0.7874 -0.4064)
			(stroke
				(width 0.1524)
				(type default)
			)
			(layer "F.SilkS")
		)
		(fp_line
			(start 0.7874 0.4064)
			(end -0.7874 0.4064)
			(stroke
				(width 0.1524)
				(type default)
			)
			(layer "F.SilkS")
		)
		(fp_line
			(start -0.7874 0.4064)
			(end -0.7874 -0.4064)
			(stroke
				(width 0.1524)
				(type default)
			)
			(layer "F.SilkS")
		)
		(fp_line
			(start -0.12065 -0.305054)
			(end -0.12065 -0.2794)
			(stroke
				(width 0.1)
				(type default)
			)
			(layer "F.Fab")
		)
		(fp_line
			(start -0.67945 -0.305054)
			(end -0.12065 -0.305054)
			(stroke
				(width 0.1)
				(type default)
			)
			(layer "F.Fab")
		)
		(fp_line
			(start 0.67945 -0.3048)
			(end 0.67945 0.3048)
			(stroke
				(width 0.1)
				(type default)
			)
			(layer "F.Fab")
		)
		(fp_line
			(start 0.12065 -0.3048)
			(end 0.67945 -0.3048)
			(stroke
				(width 0.1)
				(type default)
			)
			(layer "F.Fab")
		)
		(fp_line
			(start 0.12065 -0.2794)
			(end 0.12065 -0.3048)
			(stroke
				(width 0.1)
				(type default)
			)
			(layer "F.Fab")
		)
		(fp_line
			(start -0.12065 -0.2794)
			(end 0.12065 -0.2794)
			(stroke
				(width 0.1)
				(type default)
			)
			(layer "F.Fab")
		)
		(fp_line
			(start 0.120396 0.2794)
			(end -0.12065 0.2794)
			(stroke
				(width 0.1)
				(type default)
			)
			(layer "F.Fab")
		)
		(fp_line
			(start -0.12065 0.2794)
			(end -0.12065 0.3048)
			(stroke
				(width 0.1)
				(type default)
			)
			(layer "F.Fab")
		)
		(fp_line
			(start 0.67945 0.3048)
			(end 0.120396 0.3048)
			(stroke
				(width 0.1)
				(type default)
			)
			(layer "F.Fab")
		)
		(fp_line
			(start 0.120396 0.3048)
			(end 0.120396 0.2794)
			(stroke
				(width 0.1)
				(type default)
			)
			(layer "F.Fab")
		)
		(fp_line
			(start -0.12065 0.3048)
			(end -0.67945 0.3048)
			(stroke
				(width 0.1)
				(type default)
			)
			(layer "F.Fab")
		)
		(fp_line
			(start -0.67945 0.3048)
			(end -0.67945 -0.305054)
			(stroke
				(width 0.1)
				(type default)
			)
			(layer "F.Fab")
		)
		(pad "1" smd circle
			(at -0.40005 0 90)
			(size 0 0)
			(layers "F.Cu" "F.Mask" "F.Paste")
			(net "P12V_E1S_CB_0")
		)
		(pad "2" smd circle
			(at 0.40005 0 90)
			(size 0 0)
			(layers "F.Cu" "F.Mask" "F.Paste")
			(net "GND")
		)
	)
	(footprint ""
		(layer "F.Cu")
		(at 204.689456 -340.553548)
		(property "Reference" "PC127"
			(at 0 0 0)
			(layer "F.SilkS")
			(hide yes)
			(effects
				(font
					(size 1.27 1.27)
				)
			)
		)
		(property "Value" ""
			(at 0 0 0)
			(layer "F.Fab")
			(effects
				(font
					(size 1.27 1.27)
				)
			)
		)
		(duplicate_pad_numbers_are_jumpers no)
		(fp_line
			(start -0.7874 -0.4064)
			(end 0.7874 -0.4064)
			(stroke
				(width 0.1524)
				(type default)
			)
			(layer "F.SilkS")
		)
		(fp_line
			(start -0.7874 0.4064)
			(end -0.7874 -0.4064)
			(stroke
				(width 0.1524)
				(type default)
			)
			(layer "F.SilkS")
		)
		(fp_line
			(start 0.7874 -0.4064)
			(end 0.7874 0.4064)
			(stroke
				(width 0.1524)
				(type default)
			)
			(layer "F.SilkS")
		)
		(fp_line
			(start 0.7874 0.4064)
			(end -0.7874 0.4064)
			(stroke
				(width 0.1524)
				(type default)
			)
			(layer "F.SilkS")
		)
		(fp_line
			(start -0.67945 -0.305054)
			(end -0.12065 -0.305054)
			(stroke
				(width 0.1)
				(type default)
			)
			(layer "F.Fab")
		)
		(fp_line
			(start -0.67945 0.3048)
			(end -0.67945 -0.305054)
			(stroke
				(width 0.1)
				(type default)
			)
			(layer "F.Fab")
		)
		(fp_line
			(start -0.12065 -0.305054)
			(end -0.12065 -0.2794)
			(stroke
				(width 0.1)
				(type default)
			)
			(layer "F.Fab")
		)
		(fp_line
			(start -0.12065 -0.2794)
			(end 0.12065 -0.2794)
			(stroke
				(width 0.1)
				(type default)
			)
			(layer "F.Fab")
		)
		(fp_line
			(start -0.12065 0.2794)
			(end -0.12065 0.3048)
			(stroke
				(width 0.1)
				(type default)
			)
			(layer "F.Fab")
		)
		(fp_line
			(start -0.12065 0.3048)
			(end -0.67945 0.3048)
			(stroke
				(width 0.1)
				(type default)
			)
			(layer "F.Fab")
		)
		(fp_line
			(start 0.120396 0.2794)
			(end -0.12065 0.2794)
			(stroke
				(width 0.1)
				(type default)
			)
			(layer "F.Fab")
		)
		(fp_line
			(start 0.120396 0.3048)
			(end 0.120396 0.2794)
			(stroke
				(width 0.1)
				(type default)
			)
			(layer "F.Fab")
		)
		(fp_line
			(start 0.12065 -0.3048)
			(end 0.67945 -0.3048)
			(stroke
				(width 0.1)
				(type default)
			)
			(layer "F.Fab")
		)
		(fp_line
			(start 0.12065 -0.2794)
			(end 0.12065 -0.3048)
			(stroke
				(width 0.1)
				(type default)
			)
			(layer "F.Fab")
		)
		(fp_line
			(start 0.67945 -0.3048)
			(end 0.67945 0.3048)
			(stroke
				(width 0.1)
				(type default)
			)
			(layer "F.Fab")
		)
		(fp_line
			(start 0.67945 0.3048)
			(end 0.120396 0.3048)
			(stroke
				(width 0.1)
				(type default)
			)
			(layer "F.Fab")
		)
		(pad "1" smd circle
			(at -0.40005 0)
			(size 0 0)
			(layers "F.Cu" "F.Mask" "F.Paste")
			(net "PVDD_33_S5_REF")
		)
		(pad "2" smd circle
			(at 0.40005 0)
			(size 0 0)
			(layers "F.Cu" "F.Mask" "F.Paste")
			(net "GND")
		)
	)
	(footprint ""
		(layer "F.Cu")
		(at 18.158968 -400.099276 180)
		(property "Reference" "PC6619"
			(at 8.887968 0.051054 0)
			(unlocked yes)
			(layer "F.SilkS")
			(effects
				(font
					(size 0.7874 0.5842)
					(thickness 0.1524)
				)
				(justify left)
			)
		)
		(property "Value" ""
			(at 0 0 180)
			(layer "F.Fab")
			(effects
				(font
					(size 1.27 1.27)
				)
			)
		)
		(duplicate_pad_numbers_are_jumpers no)
		(fp_line
			(start 2.750058 2.750058)
			(end 2.750058 0.9398)
			(stroke
				(width 0.1524)
				(type default)
			)
			(layer "F.SilkS")
		)
		(fp_line
			(start 2.750058 -0.9398)
			(end 2.750058 -2.750058)
			(stroke
				(width 0.1524)
				(type default)
			)
			(layer "F.SilkS")
		)
		(fp_line
			(start 2.750058 -2.750058)
			(end -1.988058 -2.750058)
			(stroke
				(width 0.1524)
				(type default)
			)
			(layer "F.SilkS")
		)
		(fp_line
			(start -1.988058 2.750058)
			(end 2.750058 2.750058)
			(stroke
				(width 0.1524)
				(type default)
			)
			(layer "F.SilkS")
		)
		(fp_line
			(start -1.988058 -2.750058)
			(end -2.750058 -1.988058)
			(stroke
				(width 0.1524)
				(type default)
			)
			(layer "F.SilkS")
		)
		(fp_line
			(start -2.750058 1.988058)
			(end -1.988058 2.750058)
			(stroke
				(width 0.1524)
				(type default)
			)
			(layer "F.SilkS")
		)
		(fp_line
			(start -2.750058 0.9398)
			(end -2.750058 1.988058)
			(stroke
				(width 0.1524)
				(type default)
			)
			(layer "F.SilkS")
		)
		(fp_line
			(start -2.750058 -1.988058)
			(end -2.750058 -0.9398)
			(stroke
				(width 0.1524)
				(type default)
			)
			(layer "F.SilkS")
		)
		(fp_line
			(start 2.750058 2.750058)
			(end 2.750058 -2.750058)
			(stroke
				(width 0.1)
				(type default)
			)
			(layer "F.Fab")
		)
		(fp_line
			(start 2.750058 -2.750058)
			(end -2.750058 -2.750058)
			(stroke
				(width 0.1)
				(type default)
			)
			(layer "F.Fab")
		)
		(fp_line
			(start -2.750058 2.750058)
			(end 2.750058 2.750058)
			(stroke
				(width 0.1)
				(type default)
			)
			(layer "F.Fab")
		)
		(fp_line
			(start -2.750058 -2.750058)
			(end -2.750058 2.750058)
			(stroke
				(width 0.1)
				(type default)
			)
			(layer "F.Fab")
		)
		(pad "1" smd rect
			(at -2.199894 0 270)
			(size 1.6002 3.0226)
			(layers "F.Cu" "F.Mask" "F.Paste")
			(net "SW_P12V_AUX_P0V9_RETIMER_CPU1_FLT")
		)
		(pad "2" smd rect
			(at 2.199894 0 270)
			(size 1.6002 3.0226)
			(layers "F.Cu" "F.Mask" "F.Paste")
			(net "GND")
		)
	)
	(footprint ""
		(layer "F.Cu")
		(at 208.894426 -116.673376 180)
		(property "Reference" "R2939"
			(at 0 0 180)
			(layer "F.SilkS")
			(hide yes)
			(effects
				(font
					(size 1.27 1.27)
				)
			)
		)
		(property "Value" ""
			(at 0 0 180)
			(layer "F.Fab")
			(effects
				(font
					(size 1.27 1.27)
				)
			)
		)
		(duplicate_pad_numbers_are_jumpers no)
		(fp_line
			(start 0.7874 0.4064)
			(end -0.7874 0.4064)
			(stroke
				(width 0.1524)
				(type default)
			)
			(layer "F.SilkS")
		)
		(fp_line
			(start 0.7874 -0.4064)
			(end 0.7874 0.4064)
			(stroke
				(width 0.1524)
				(type default)
			)
			(layer "F.SilkS")
		)
		(fp_line
			(start -0.7874 0.4064)
			(end -0.7874 -0.4064)
			(stroke
				(width 0.1524)
				(type default)
			)
			(layer "F.SilkS")
		)
		(fp_line
			(start -0.7874 -0.4064)
			(end 0.7874 -0.4064)
			(stroke
				(width 0.1524)
				(type default)
			)
			(layer "F.SilkS")
		)
		(fp_line
			(start 0.67945 0.3048)
			(end 0.120396 0.3048)
			(stroke
				(width 0.1)
				(type default)
			)
			(layer "F.Fab")
		)
		(fp_line
			(start 0.67945 -0.3048)
			(end 0.67945 0.3048)
			(stroke
				(width 0.1)
				(type default)
			)
			(layer "F.Fab")
		)
		(fp_line
			(start 0.12065 -0.2794)
			(end 0.12065 -0.3048)
			(stroke
				(width 0.1)
				(type default)
			)
			(layer "F.Fab")
		)
		(fp_line
			(start 0.12065 -0.3048)
			(end 0.67945 -0.3048)
			(stroke
				(width 0.1)
				(type default)
			)
			(layer "F.Fab")
		)
		(fp_line
			(start 0.120396 0.3048)
			(end 0.120396 0.2794)
			(stroke
				(width 0.1)
				(type default)
			)
			(layer "F.Fab")
		)
		(fp_line
			(start 0.120396 0.2794)
			(end -0.12065 0.2794)
			(stroke
				(width 0.1)
				(type default)
			)
			(layer "F.Fab")
		)
		(fp_line
			(start -0.12065 0.3048)
			(end -0.67945 0.3048)
			(stroke
				(width 0.1)
				(type default)
			)
			(layer "F.Fab")
		)
		(fp_line
			(start -0.12065 0.2794)
			(end -0.12065 0.3048)
			(stroke
				(width 0.1)
				(type default)
			)
			(layer "F.Fab")
		)
		(fp_line
			(start -0.12065 -0.2794)
			(end 0.12065 -0.2794)
			(stroke
				(width 0.1)
				(type default)
			)
			(layer "F.Fab")
		)
		(fp_line
			(start -0.12065 -0.305054)
			(end -0.12065 -0.2794)
			(stroke
				(width 0.1)
				(type default)
			)
			(layer "F.Fab")
		)
		(fp_line
			(start -0.67945 0.3048)
			(end -0.67945 -0.305054)
			(stroke
				(width 0.1)
				(type default)
			)
			(layer "F.Fab")
		)
		(fp_line
			(start -0.67945 -0.305054)
			(end -0.12065 -0.305054)
			(stroke
				(width 0.1)
				(type default)
			)
			(layer "F.Fab")
		)
		(pad "1" smd circle
			(at -0.40005 0 180)
			(size 0 0)
			(layers "F.Cu" "F.Mask" "F.Paste")
			(net "FM_GPU_HSC_EN")
		)
		(pad "2" smd circle
			(at 0.40005 0 180)
			(size 0 0)
			(layers "F.Cu" "F.Mask" "F.Paste")
			(net "FM_GPU_HSC_EN_R")
		)
	)
	(footprint ""
		(layer "F.Cu")
		(at 240.771426 -294.597074 180)
		(property "Reference" "PR6800"
			(at 0 0 180)
			(layer "F.SilkS")
			(hide yes)
			(effects
				(font
					(size 1.27 1.27)
				)
			)
		)
		(property "Value" ""
			(at 0 0 180)
			(layer "F.Fab")
			(effects
				(font
					(size 1.27 1.27)
				)
			)
		)
		(duplicate_pad_numbers_are_jumpers no)
		(fp_line
			(start 0.7874 0.4064)
			(end -0.7874 0.4064)
			(stroke
				(width 0.1524)
				(type default)
			)
			(layer "F.SilkS")
		)
		(fp_line
			(start 0.7874 -0.4064)
			(end 0.7874 0.4064)
			(stroke
				(width 0.1524)
				(type default)
			)
			(layer "F.SilkS")
		)
		(fp_line
			(start -0.7874 0.4064)
			(end -0.7874 -0.4064)
			(stroke
				(width 0.1524)
				(type default)
			)
			(layer "F.SilkS")
		)
		(fp_line
			(start -0.7874 -0.4064)
			(end 0.7874 -0.4064)
			(stroke
				(width 0.1524)
				(type default)
			)
			(layer "F.SilkS")
		)
		(fp_line
			(start 0.67945 0.3048)
			(end 0.120396 0.3048)
			(stroke
				(width 0.1)
				(type default)
			)
			(layer "F.Fab")
		)
		(fp_line
			(start 0.67945 -0.3048)
			(end 0.67945 0.3048)
			(stroke
				(width 0.1)
				(type default)
			)
			(layer "F.Fab")
		)
		(fp_line
			(start 0.12065 -0.2794)
			(end 0.12065 -0.3048)
			(stroke
				(width 0.1)
				(type default)
			)
			(layer "F.Fab")
		)
		(fp_line
			(start 0.12065 -0.3048)
			(end 0.67945 -0.3048)
			(stroke
				(width 0.1)
				(type default)
			)
			(layer "F.Fab")
		)
		(fp_line
			(start 0.120396 0.3048)
			(end 0.120396 0.2794)
			(stroke
				(width 0.1)
				(type default)
			)
			(layer "F.Fab")
		)
		(fp_line
			(start 0.120396 0.2794)
			(end -0.12065 0.2794)
			(stroke
				(width 0.1)
				(type default)
			)
			(layer "F.Fab")
		)
		(fp_line
			(start -0.12065 0.3048)
			(end -0.67945 0.3048)
			(stroke
				(width 0.1)
				(type default)
			)
			(layer "F.Fab")
		)
		(fp_line
			(start -0.12065 0.2794)
			(end -0.12065 0.3048)
			(stroke
				(width 0.1)
				(type default)
			)
			(layer "F.Fab")
		)
		(fp_line
			(start -0.12065 -0.2794)
			(end 0.12065 -0.2794)
			(stroke
				(width 0.1)
				(type default)
			)
			(layer "F.Fab")
		)
		(fp_line
			(start -0.12065 -0.305054)
			(end -0.12065 -0.2794)
			(stroke
				(width 0.1)
				(type default)
			)
			(layer "F.Fab")
		)
		(fp_line
			(start -0.67945 0.3048)
			(end -0.67945 -0.305054)
			(stroke
				(width 0.1)
				(type default)
			)
			(layer "F.Fab")
		)
		(fp_line
			(start -0.67945 -0.305054)
			(end -0.12065 -0.305054)
			(stroke
				(width 0.1)
				(type default)
			)
			(layer "F.Fab")
		)
		(pad "1" smd circle
			(at -0.40005 0 180)
			(size 0 0)
			(layers "F.Cu" "F.Mask" "F.Paste")
			(net "SW_P1V8_RETIMER_CPU0_BST")
		)
		(pad "2" smd circle
			(at 0.40005 0 180)
			(size 0 0)
			(layers "F.Cu" "F.Mask" "F.Paste")
			(net "SW_P1V8_RETIMER_CPU0_BST_R")
		)
	)
	(footprint ""
		(layer "F.Cu")
		(at 299.935646 -117.65026 90)
		(property "Reference" "R3587"
			(at 0 0 90)
			(layer "F.SilkS")
			(hide yes)
			(effects
				(font
					(size 1.27 1.27)
				)
			)
		)
		(property "Value" ""
			(at 0 0 90)
			(layer "F.Fab")
			(effects
				(font
					(size 1.27 1.27)
				)
			)
		)
		(duplicate_pad_numbers_are_jumpers no)
		(fp_line
			(start 0.7874 -0.4064)
			(end 0.7874 0.4064)
			(stroke
				(width 0.1524)
				(type default)
			)
			(layer "F.SilkS")
		)
		(fp_line
			(start -0.7874 -0.4064)
			(end 0.7874 -0.4064)
			(stroke
				(width 0.1524)
				(type default)
			)
			(layer "F.SilkS")
		)
		(fp_line
			(start 0.7874 0.4064)
			(end -0.7874 0.4064)
			(stroke
				(width 0.1524)
				(type default)
			)
			(layer "F.SilkS")
		)
		(fp_line
			(start -0.7874 0.4064)
			(end -0.7874 -0.4064)
			(stroke
				(width 0.1524)
				(type default)
			)
			(layer "F.SilkS")
		)
		(fp_line
			(start -0.12065 -0.305054)
			(end -0.12065 -0.2794)
			(stroke
				(width 0.1)
				(type default)
			)
			(layer "F.Fab")
		)
		(fp_line
			(start -0.67945 -0.305054)
			(end -0.12065 -0.305054)
			(stroke
				(width 0.1)
				(type default)
			)
			(layer "F.Fab")
		)
		(fp_line
			(start 0.67945 -0.3048)
			(end 0.67945 0.3048)
			(stroke
				(width 0.1)
				(type default)
			)
			(layer "F.Fab")
		)
		(fp_line
			(start 0.12065 -0.3048)
			(end 0.67945 -0.3048)
			(stroke
				(width 0.1)
				(type default)
			)
			(layer "F.Fab")
		)
		(fp_line
			(start 0.12065 -0.2794)
			(end 0.12065 -0.3048)
			(stroke
				(width 0.1)
				(type default)
			)
			(layer "F.Fab")
		)
		(fp_line
			(start -0.12065 -0.2794)
			(end 0.12065 -0.2794)
			(stroke
				(width 0.1)
				(type default)
			)
			(layer "F.Fab")
		)
		(fp_line
			(start 0.120396 0.2794)
			(end -0.12065 0.2794)
			(stroke
				(width 0.1)
				(type default)
			)
			(layer "F.Fab")
		)
		(fp_line
			(start -0.12065 0.2794)
			(end -0.12065 0.3048)
			(stroke
				(width 0.1)
				(type default)
			)
			(layer "F.Fab")
		)
		(fp_line
			(start 0.67945 0.3048)
			(end 0.120396 0.3048)
			(stroke
				(width 0.1)
				(type default)
			)
			(layer "F.Fab")
		)
		(fp_line
			(start 0.120396 0.3048)
			(end 0.120396 0.2794)
			(stroke
				(width 0.1)
				(type default)
			)
			(layer "F.Fab")
		)
		(fp_line
			(start -0.12065 0.3048)
			(end -0.67945 0.3048)
			(stroke
				(width 0.1)
				(type default)
			)
			(layer "F.Fab")
		)
		(fp_line
			(start -0.67945 0.3048)
			(end -0.67945 -0.305054)
			(stroke
				(width 0.1)
				(type default)
			)
			(layer "F.Fab")
		)
		(pad "1" smd circle
			(at -0.40005 0 90)
			(size 0 0)
			(layers "F.Cu" "F.Mask" "F.Paste")
			(net "SMB_INA230_3V3AUX_SDA")
		)
		(pad "2" smd circle
			(at 0.40005 0 90)
			(size 0 0)
			(layers "F.Cu" "F.Mask" "F.Paste")
			(net "SMB_INA230_1_3V3AUX_SDA_R")
		)
	)
)
